#ISCELL
  mstr_symbols design_note *
  *
#ISCELL
  mstr_symbols intel_corp_bpage *
  *
#CELL
  dev_discrete cap_a *
  page76_i1
#CELL
  dev_discrete cap_a *
  page76_i10
#CELL
  mstr_discrete cap *
  page76_i100
#CELL
  mstr_discrete cap *
  page76_i101
#CELL
  mstr_discrete cap *
  page76_i103
#CELL
  mstr_discrete cap *
  page76_i105
#CELL
  mstr_discrete cap *
  page76_i106
#CELL
  mstr_discrete cap *
  page76_i107
#CELL
  dev_discrete cap_a *
  page76_i108
#ISCELL
  mstr_symbols gnd *
  page76_i109
#CELL
  dev_discrete cap_a *
  page76_i111
#CELL
  dev_discrete cap_a *
  page76_i112
#ISCELL
  mstr_symbols gnd *
  page76_i113
#CELL
  dev_discrete cap_a *
  page76_i114
#CELL
  dev_discrete cap_a *
  page76_i116
#CELL
  mstr_discrete cap *
  page76_i118
#CELL
  dev_discrete cap_a *
  page76_i119
#CELL
  dev_discrete cap_a *
  page76_i122
#CELL
  dev_discrete cap_a *
  page76_i123
#CELL
  dev_discrete cap_a *
  page76_i124
#CELL
  mstr_discrete cap *
  page76_i125
#CELL
  mstr_discrete cap *
  page76_i127
#ISCELL
  mstr_symbols gnd *
  page76_i128
#CELL
  mstr_discrete cap *
  page76_i129
#ISCELL
  mstr_symbols gnd *
  page76_i130
#CELL
  mstr_discrete cap *
  page76_i131
#CELL
  mstr_discrete cap *
  page76_i132
#CELL
  mstr_discrete cap *
  page76_i133
#ISCELL
  mstr_symbols gnd *
  page76_i134
#CELL
  mstr_discrete cap *
  page76_i135
#CELL
  mstr_discrete cap *
  page76_i136
#CELL
  mstr_discrete cap *
  page76_i137
#CELL
  mstr_discrete cap *
  page76_i139
#CELL
  mstr_discrete cap *
  page76_i141
#ISCELL
  mstr_symbols pvccin_cpu1 *
  page76_i143
#ISCELL
  mstr_symbols pvccin_cpu1 *
  page76_i144
#ISCELL
  mstr_symbols pvccin_cpu1 *
  page76_i145
#ISCELL
  mstr_symbols pvccin_cpu1 *
  page76_i146
#ISCELL
  mstr_symbols pvccin_cpu1 *
  page76_i147
#CELL
  dev_discrete cap_a *
  page76_i15
#ISCELL
  mstr_symbols pvccin_cpu1 *
  page76_i153
#ISCELL
  mstr_symbols pvccin_cpu1 *
  page76_i154
#ISCELL
  mstr_symbols pvccin_cpu1 *
  page76_i155
#ISCELL
  mstr_symbols pvccin_cpu1 *
  page76_i156
#ISCELL
  mstr_symbols pvccin_cpu1 *
  page76_i157
#ISCELL
  mstr_symbols pvccin_cpu1 *
  page76_i158
#CELL
  dev_discrete cap_a *
  page76_i159
#ISCELL
  mstr_symbols gnd *
  page76_i16
#CELL
  dev_discrete cap_a *
  page76_i160
#CELL
  dev_discrete cap_a *
  page76_i161
#ISCELL
  mstr_symbols vcc_core *
  page76_i162
#ISCELL
  mstr_symbols vcc_core *
  page76_i163
#CELL
  dev_discrete cap_a *
  page76_i164
#CELL
  dev_discrete cap_a *
  page76_i165
#CELL
  dev_discrete cap_a *
  page76_i166
#ISCELL
  mstr_symbols pvccio_cpu1 *
  page76_i167
#CELL
  dev_discrete cap_a *
  page76_i169
#CELL
  dev_discrete cap_a *
  page76_i170
#CELL
  dev_discrete cap_a *
  page76_i171
#CELL
  dev_discrete cap_a *
  page76_i172
#CELL
  dev_discrete cap_a *
  page76_i174
#CELL
  dev_discrete cap_a *
  page76_i175
#CELL
  dev_discrete cap_a *
  page76_i176
#CELL
  dev_discrete cap_a *
  page76_i179
#CELL
  dev_discrete cap_a *
  page76_i18
#CELL
  mstr_discrete cap *
  page76_i181
#CELL
  mstr_discrete cap *
  page76_i182
#CELL
  mstr_discrete cap *
  page76_i183
#CELL
  mstr_discrete cap *
  page76_i184
#CELL
  mstr_discrete cap *
  page76_i195
#CELL
  dev_discrete cap_a *
  page76_i196
#CELL
  dev_discrete cap_a *
  page76_i197
#CELL
  dev_discrete cap_a *
  page76_i198
#CELL
  dev_discrete cap_a *
  page76_i199
#ISCELL
  mstr_symbols gnd *
  page76_i2
#CELL
  dev_discrete cap_a *
  page76_i201
#CELL
  dev_discrete cap_a *
  page76_i202
#CELL
  dev_discrete cap_a *
  page76_i203
#CELL
  dev_discrete cap_a *
  page76_i204
#CELL
  dev_discrete cap_a *
  page76_i205
#CELL
  dev_discrete cap_a *
  page76_i206
#CELL
  dev_discrete cap_a *
  page76_i207
#CELL
  dev_discrete cap_a *
  page76_i208
#ISCELL
  mstr_symbols vcc_core *
  page76_i209
#ISCELL
  mstr_symbols gnd *
  page76_i210
#CELL
  mstr_discrete cap *
  page76_i211
#CELL
  mstr_discrete cap *
  page76_i212
#CELL
  mstr_discrete cap *
  page76_i213
#CELL
  mstr_discrete cap *
  page76_i214
#CELL
  mstr_discrete cap *
  page76_i215
#CELL
  mstr_discrete cap *
  page76_i216
#CELL
  mstr_discrete cap *
  page76_i217
#CELL
  mstr_discrete cap *
  page76_i218
#CELL
  mstr_discrete cap *
  page76_i23
#ISCELL
  mstr_symbols gnd *
  page76_i24
#CELL
  mstr_discrete cap *
  page76_i25
#CELL
  mstr_discrete cap *
  page76_i26
#CELL
  mstr_discrete cap *
  page76_i27
#CELL
  mstr_discrete cap *
  page76_i28
#CELL
  mstr_discrete cap *
  page76_i29
#CELL
  dev_discrete cap_a *
  page76_i3
#ISCELL
  mstr_symbols gnd *
  page76_i30
#CELL
  mstr_discrete cap *
  page76_i33
#ISCELL
  mstr_symbols gnd *
  page76_i36
#CELL
  mstr_discrete cap *
  page76_i37
#CELL
  dev_discrete cap_a *
  page76_i4
#ISCELL
  mstr_symbols pvsa_cpu1 *
  page76_i41
#CELL
  mstr_discrete cap *
  page76_i42
#CELL
  mstr_discrete cap *
  page76_i43
#CELL
  mstr_discrete cap *
  page76_i45
#ISCELL
  mstr_symbols pvccio_cpu1 *
  page76_i47
#CELL
  mstr_discrete cap *
  page76_i48
#CELL
  mstr_discrete cap *
  page76_i49
#CELL
  dev_discrete cap_a *
  page76_i5
#CELL
  mstr_discrete cap *
  page76_i50
#CELL
  mstr_discrete cap *
  page76_i51
#CELL
  mstr_discrete cap *
  page76_i52
#ISCELL
  mstr_symbols gnd *
  page76_i53
#CELL
  mstr_discrete cap *
  page76_i55
#ISCELL
  mstr_symbols pvsa_cpu1 *
  page76_i57
#CELL
  mstr_discrete cap *
  page76_i58
#CELL
  dev_discrete cap_a *
  page76_i59
#ISCELL
  mstr_symbols gnd *
  page76_i60
#CELL
  dev_discrete cap_a *
  page76_i61
#CELL
  dev_discrete cap_a *
  page76_i63
#CELL
  dev_discrete cap_a *
  page76_i65
#CELL
  dev_discrete cap_a *
  page76_i66
#ISCELL
  mstr_symbols gnd *
  page76_i67
#CELL
  dev_discrete cap_a *
  page76_i69
#CELL
  dev_discrete cap_a *
  page76_i7
#CELL
  dev_discrete cap_a *
  page76_i70
#ISCELL
  mstr_symbols pvccin_cpu1 *
  page76_i71
#CELL
  dev_discrete cap_a *
  page76_i73
#ISCELL
  mstr_symbols gnd *
  page76_i74
#CELL
  dev_discrete cap_a *
  page76_i75
#CELL
  dev_discrete cap_a *
  page76_i76
#ISCELL
  mstr_symbols gnd *
  page76_i77
#CELL
  dev_discrete cap_a *
  page76_i79
#CELL
  dev_discrete cap_a *
  page76_i8
#CELL
  dev_discrete cap_a *
  page76_i80
#CELL
  dev_discrete cap_a *
  page76_i82
#CELL
  dev_discrete cap_a *
  page76_i83
#CELL
  dev_discrete cap_a *
  page76_i85
#CELL
  mstr_discrete cap *
  page76_i88
#CELL
  mstr_discrete cap *
  page76_i89
#CELL
  dev_discrete cap_a *
  page76_i90
#CELL
  mstr_discrete cap *
  page76_i92
#ISCELL
  mstr_symbols gnd *
  page76_i93
#ISCELL
  mstr_symbols gnd *
  page76_i95
#ISCELL
  mstr_symbols gnd *
  page76_i97
